# S9S_MB_2U (Grand Teton) — schematic netlist excerpt (pin names and nets, part order shuffled) for the footprints in the layout excerpt that follows; sources: Cadence DE-HDL packaged netlist, KiCad conversion of 03242023_DA0F0TMBIJ0_F0T_Motherboard_J_brd_V01_OCP.brd

R3906  Q_RES  49.9 1% CHIP  pkg 0402LF  page 113 : A = I3C_SPD_DDREFGH_CPU1_LVC1_SCL_7 ; B = I3C_SPD_DDREFGH_CPU1_LVC1_SCL
C35  Q_CAP  2.2UF 6.3V 20% X6S  pkg C0402  page 93 : A = P3V3_AUX ; B = GND
C76  Q_CAP  10UF 16V 10% X6S  pkg C0805  page 112 : A = P12V_S3_AUX_CPU1_NVDIMM ; B = GND

(kicad_pcb
	(version 20260206)
	(generator "pcbnew")
	(generator_version "10.0")
	(general
		(thickness 1.6)
		(legacy_teardrops no)
	)
	(paper "A4")
	(title_block
		(title "03242023_DA0F0TMBIJ0_F0T_Motherboard_J_brd_V01_OCP.brd")
		(comment 1 "Grand Teton / footprints 6041-6043 of 6105")
	)
	(layers
		(0 "F.Cu" signal "TOP")
		(4 "In1.Cu" signal "GND")
		(6 "In2.Cu" signal "IN1")
		(8 "In3.Cu" signal "GND1")
		(10 "In4.Cu" signal "IN2")
		(12 "In5.Cu" signal "GND2")
		(14 "In6.Cu" signal "IN3")
		(16 "In7.Cu" signal "GND3")
		(18 "In8.Cu" signal "VCC")
		(20 "In9.Cu" signal "VCC1")
		(22 "In10.Cu" signal "GND4")
		(24 "In11.Cu" signal "IN4")
		(26 "In12.Cu" signal "GND5")
		(28 "In13.Cu" signal "IN5")
		(30 "In14.Cu" signal "GND6")
		(32 "In15.Cu" signal "IN6")
		(34 "In16.Cu" signal "GND7")
		(2 "B.Cu" signal "BOTTOM")
		(9 "F.Adhes" user "F.Adhesive")
		(11 "B.Adhes" user "B.Adhesive")
		(13 "F.Paste" user "Package Geometry/Pastemask Top")
		(15 "B.Paste" user "Package Geometry/Pastemask Bottom")
		(5 "F.SilkS" user "Ref Des/Silkscreen Top")
		(7 "B.SilkS" user "Ref Des/Silkscreen Bottom")
		(1 "F.Mask" user "Board Geometry/Soldermask Top")
		(3 "B.Mask" user "Board Geometry/Soldermask Bottom")
		(17 "Dwgs.User" user "User.Drawings")
		(19 "Cmts.User" user "User.Comments")
		(21 "Eco1.User" user "User.Eco1")
		(23 "Eco2.User" user "User.Eco2")
		(25 "Edge.Cuts" user "Board Geometry/Outline")
		(27 "Margin" user)
		(31 "F.CrtYd" user "Package Geometry/Place Bound Top")
		(29 "B.CrtYd" user "Package Geometry/Place Bound Bottom")
		(35 "F.Fab" user "Ref Des/Assembly Top")
		(33 "B.Fab" user "Ref Des/Assembly Bottom")
	)
	(footprint ""
		(layer "B.Cu")
		(at 211.632546 -321.554856 -90)
		(property "Reference" "C76"
			(at 0 0 90)
			(layer "B.SilkS")
			(hide yes)
			(effects
				(font
					(size 1.27 1.27)
				)
				(justify mirror)
			)
		)
		(property "Value" ""
			(at 0 0 90)
			(layer "B.Fab")
			(effects
				(font
					(size 1.27 1.27)
				)
				(justify mirror)
			)
		)
		(duplicate_pad_numbers_are_jumpers no)
		(fp_line
			(start -1.524 0.762)
			(end 1.524 0.762)
			(stroke
				(width 0.1524)
				(type default)
			)
			(layer "B.SilkS")
		)
		(fp_line
			(start 1.524 0.762)
			(end 1.524 -0.762)
			(stroke
				(width 0.1524)
				(type default)
			)
			(layer "B.SilkS")
		)
		(fp_line
			(start -1.524 -0.762)
			(end -1.524 0.762)
			(stroke
				(width 0.1524)
				(type default)
			)
			(layer "B.SilkS")
		)
		(fp_line
			(start 1.524 -0.762)
			(end -1.524 -0.762)
			(stroke
				(width 0.1524)
				(type default)
			)
			(layer "B.SilkS")
		)
		(fp_line
			(start -1.1049 0.724916)
			(end -1.1049 -0.724916)
			(stroke
				(width 0.1)
				(type default)
			)
			(layer "B.Fab")
		)
		(fp_line
			(start 1.1049 0.724916)
			(end -1.1049 0.724916)
			(stroke
				(width 0.1)
				(type default)
			)
			(layer "B.Fab")
		)
		(fp_line
			(start -1.1049 -0.724916)
			(end 1.1049 -0.724916)
			(stroke
				(width 0.1)
				(type default)
			)
			(layer "B.Fab")
		)
		(fp_line
			(start 1.1049 -0.724916)
			(end 1.1049 0.724916)
			(stroke
				(width 0.1)
				(type default)
			)
			(layer "B.Fab")
		)
		(pad "1" smd rect
			(at 0.889 0 270)
			(size 1.016 1.27)
			(layers "B.Cu" "B.Mask" "B.Paste")
			(net "P12V_S3_AUX_CPU1_NVDIMM")
		)
		(pad "2" smd rect
			(at -0.889 0 270)
			(size 1.016 1.27)
			(layers "B.Cu" "B.Mask" "B.Paste")
			(net "GND")
		)
	)
	(footprint ""
		(layer "B.Cu")
		(at 203.991464 -316.386718 90)
		(property "Reference" "R3906"
			(at 0 0 90)
			(layer "B.SilkS")
			(hide yes)
			(effects
				(font
					(size 1.27 1.27)
				)
				(justify mirror)
			)
		)
		(property "Value" ""
			(at 0 0 90)
			(layer "B.Fab")
			(effects
				(font
					(size 1.27 1.27)
				)
				(justify mirror)
			)
		)
		(duplicate_pad_numbers_are_jumpers no)
		(fp_line
			(start 0.7874 -0.4064)
			(end -0.7874 -0.4064)
			(stroke
				(width 0.1524)
				(type default)
			)
			(layer "B.SilkS")
		)
		(fp_line
			(start -0.7874 -0.4064)
			(end -0.7874 0.4064)
			(stroke
				(width 0.1524)
				(type default)
			)
			(layer "B.SilkS")
		)
		(fp_line
			(start 0.7874 0.4064)
			(end 0.7874 -0.4064)
			(stroke
				(width 0.1524)
				(type default)
			)
			(layer "B.SilkS")
		)
		(fp_line
			(start -0.7874 0.4064)
			(end 0.7874 0.4064)
			(stroke
				(width 0.1524)
				(type default)
			)
			(layer "B.SilkS")
		)
		(fp_line
			(start 0.67945 -0.305054)
			(end 0.12065 -0.305054)
			(stroke
				(width 0.1)
				(type default)
			)
			(layer "B.Fab")
		)
		(fp_line
			(start 0.12065 -0.305054)
			(end 0.12065 -0.2794)
			(stroke
				(width 0.1)
				(type default)
			)
			(layer "B.Fab")
		)
		(fp_line
			(start -0.12065 -0.3048)
			(end -0.67945 -0.3048)
			(stroke
				(width 0.1)
				(type default)
			)
			(layer "B.Fab")
		)
		(fp_line
			(start -0.67945 -0.3048)
			(end -0.67945 0.3048)
			(stroke
				(width 0.1)
				(type default)
			)
			(layer "B.Fab")
		)
		(fp_line
			(start 0.12065 -0.2794)
			(end -0.12065 -0.2794)
			(stroke
				(width 0.1)
				(type default)
			)
			(layer "B.Fab")
		)
		(fp_line
			(start -0.12065 -0.2794)
			(end -0.12065 -0.3048)
			(stroke
				(width 0.1)
				(type default)
			)
			(layer "B.Fab")
		)
		(fp_line
			(start 0.12065 0.2794)
			(end 0.12065 0.3048)
			(stroke
				(width 0.1)
				(type default)
			)
			(layer "B.Fab")
		)
		(fp_line
			(start -0.120396 0.2794)
			(end 0.12065 0.2794)
			(stroke
				(width 0.1)
				(type default)
			)
			(layer "B.Fab")
		)
		(fp_line
			(start 0.67945 0.3048)
			(end 0.67945 -0.305054)
			(stroke
				(width 0.1)
				(type default)
			)
			(layer "B.Fab")
		)
		(fp_line
			(start 0.12065 0.3048)
			(end 0.67945 0.3048)
			(stroke
				(width 0.1)
				(type default)
			)
			(layer "B.Fab")
		)
		(fp_line
			(start -0.120396 0.3048)
			(end -0.120396 0.2794)
			(stroke
				(width 0.1)
				(type default)
			)
			(layer "B.Fab")
		)
		(fp_line
			(start -0.67945 0.3048)
			(end -0.120396 0.3048)
			(stroke
				(width 0.1)
				(type default)
			)
			(layer "B.Fab")
		)
		(pad "1" smd circle
			(at 0.40005 0 270)
			(size 0 0)
			(layers "B.Cu" "B.Mask" "B.Paste")
			(net "I3C_SPD_DDREFGH_CPU1_LVC1_SCL_7")
		)
		(pad "2" smd circle
			(at -0.40005 0 270)
			(size 0 0)
			(layers "B.Cu" "B.Mask" "B.Paste")
			(net "I3C_SPD_DDREFGH_CPU1_LVC1_SCL")
		)
	)
	(footprint ""
		(layer "B.Cu")
		(at 421.853614 -319.263776 180)
		(property "Reference" "C35"
			(at 0 0 0)
			(layer "B.SilkS")
			(hide yes)
			(effects
				(font
					(size 1.27 1.27)
				)
				(justify mirror)
			)
		)
		(property "Value" ""
			(at 0 0 0)
			(layer "B.Fab")
			(effects
				(font
					(size 1.27 1.27)
				)
				(justify mirror)
			)
		)
		(duplicate_pad_numbers_are_jumpers no)
		(fp_line
			(start 0.7874 0.4064)
			(end 0.7874 -0.4064)
			(stroke
				(width 0.1524)
				(type default)
			)
			(layer "B.SilkS")
		)
		(fp_line
			(start 0.7874 -0.4064)
			(end -0.7874 -0.4064)
			(stroke
				(width 0.1524)
				(type default)
			)
			(layer "B.SilkS")
		)
		(fp_line
			(start -0.7874 0.4064)
			(end 0.7874 0.4064)
			(stroke
				(width 0.1524)
				(type default)
			)
			(layer "B.SilkS")
		)
		(fp_line
			(start -0.7874 -0.4064)
			(end -0.7874 0.4064)
			(stroke
				(width 0.1524)
				(type default)
			)
			(layer "B.SilkS")
		)
		(fp_line
			(start 0.67945 0.3048)
			(end 0.67945 -0.305054)
			(stroke
				(width 0.1)
				(type default)
			)
			(layer "B.Fab")
		)
		(fp_line
			(start 0.67945 -0.305054)
			(end 0.12065 -0.305054)
			(stroke
				(width 0.1)
				(type default)
			)
			(layer "B.Fab")
		)
		(fp_line
			(start 0.12065 0.3048)
			(end 0.67945 0.3048)
			(stroke
				(width 0.1)
				(type default)
			)
			(layer "B.Fab")
		)
		(fp_line
			(start 0.12065 0.2794)
			(end 0.12065 0.3048)
			(stroke
				(width 0.1)
				(type default)
			)
			(layer "B.Fab")
		)
		(fp_line
			(start 0.12065 -0.2794)
			(end -0.12065 -0.2794)
			(stroke
				(width 0.1)
				(type default)
			)
			(layer "B.Fab")
		)
		(fp_line
			(start 0.12065 -0.305054)
			(end 0.12065 -0.2794)
			(stroke
				(width 0.1)
				(type default)
			)
			(layer "B.Fab")
		)
		(fp_line
			(start -0.120396 0.3048)
			(end -0.120396 0.2794)
			(stroke
				(width 0.1)
				(type default)
			)
			(layer "B.Fab")
		)
		(fp_line
			(start -0.120396 0.2794)
			(end 0.12065 0.2794)
			(stroke
				(width 0.1)
				(type default)
			)
			(layer "B.Fab")
		)
		(fp_line
			(start -0.12065 -0.2794)
			(end -0.12065 -0.3048)
			(stroke
				(width 0.1)
				(type default)
			)
			(layer "B.Fab")
		)
		(fp_line
			(start -0.12065 -0.3048)
			(end -0.67945 -0.3048)
			(stroke
				(width 0.1)
				(type default)
			)
			(layer "B.Fab")
		)
		(fp_line
			(start -0.67945 0.3048)
			(end -0.120396 0.3048)
			(stroke
				(width 0.1)
				(type default)
			)
			(layer "B.Fab")
		)
		(fp_line
			(start -0.67945 -0.3048)
			(end -0.67945 0.3048)
			(stroke
				(width 0.1)
				(type default)
			)
			(layer "B.Fab")
		)
		(pad "1" smd circle
			(at 0.40005 0)
			(size 0 0)
			(layers "B.Cu" "B.Mask" "B.Paste")
			(net "P3V3_AUX")
		)
		(pad "2" smd circle
			(at -0.40005 0)
			(size 0 0)
			(layers "B.Cu" "B.Mask" "B.Paste")
			(net "GND")
		)
	)
)
